(kicad_pcb
	(version 20260206)
	(generator "pcbnew")
	(generator_version "10.0")
	(general
		(thickness 1.6)
		(legacy_teardrops no)
	)
	(paper "A4")
	(title_block
		(title "Wiwynn_Tioga_Pass_MB.brd")
		(comment 1 "Tioga Pass / footprints 80-86 of 4770")
	)
	(layers
		(0 "F.Cu" signal "TOP")
		(4 "In1.Cu" signal "L2GND")
		(6 "In2.Cu" signal "L3")
		(8 "In3.Cu" signal "L4GND")
		(10 "In4.Cu" signal "L5")
		(12 "In5.Cu" signal "L6GND")
		(14 "In6.Cu" signal "L7VCC")
		(16 "In7.Cu" signal "L8VCC")
		(18 "In8.Cu" signal "L9GND")
		(20 "In9.Cu" signal "L10")
		(22 "In10.Cu" signal "L11GND")
		(24 "In11.Cu" signal "L12")
		(26 "In12.Cu" signal "L13GND")
		(2 "B.Cu" signal "BOTTOM")
		(9 "F.Adhes" user "F.Adhesive")
		(11 "B.Adhes" user "B.Adhesive")
		(13 "F.Paste" user "Package Geometry/Pastemask Top")
		(15 "B.Paste" user "Package Geometry/Pastemask Bottom")
		(5 "F.SilkS" user "Ref Des/Silkscreen Top")
		(7 "B.SilkS" user "Ref Des/Silkscreen Bottom")
		(1 "F.Mask" user "Board Geometry/Soldermask Top")
		(3 "B.Mask" user "Board Geometry/Soldermask Bottom")
		(17 "Dwgs.User" user "User.Drawings")
		(19 "Cmts.User" user "User.Comments")
		(21 "Eco1.User" user "User.Eco1")
		(23 "Eco2.User" user "User.Eco2")
		(25 "Edge.Cuts" user "Board Geometry/Outline")
		(27 "Margin" user)
		(31 "F.CrtYd" user "Package Geometry/Place Bound Top")
		(29 "B.CrtYd" user "Package Geometry/Place Bound Bottom")
		(35 "F.Fab" user "Ref Des/Assembly Top")
		(33 "B.Fab" user "Ref Des/Assembly Bottom")
	)
	(footprint ""
		(layer "F.Cu")
		(at 391.55624 -152.008586 -90)
		(property "Reference" "C8A3"
			(at 0 0 270)
			(layer "F.SilkS")
			(hide yes)
			(effects
				(font
					(size 1.27 1.27)
				)
			)
		)
		(property "Value" ""
			(at 0 0 270)
			(layer "F.Fab")
			(effects
				(font
					(size 1.27 1.27)
				)
			)
		)
		(duplicate_pad_numbers_are_jumpers no)
		(fp_poly
			(pts
				(xy 0.3048 -0.1016) (xy 0.3048 0.9906) (xy -0.3048 0.9906) (xy -0.3048 -0.1016)
			)
			(stroke
				(width 0)
				(type default)
			)
			(fill no)
			(layer "F.CrtYd")
		)
		(fp_line
			(start -0.3048 0.9906)
			(end 0.3048 0.9906)
			(stroke
				(width 0.1)
				(type default)
			)
			(layer "F.Fab")
		)
		(fp_line
			(start 0.3048 0.9906)
			(end 0.3048 -0.1016)
			(stroke
				(width 0.1)
				(type default)
			)
			(layer "F.Fab")
		)
		(fp_line
			(start -0.3048 -0.1016)
			(end -0.3048 0.9906)
			(stroke
				(width 0.1)
				(type default)
			)
			(layer "F.Fab")
		)
		(fp_line
			(start 0.3048 -0.1016)
			(end -0.3048 -0.1016)
			(stroke
				(width 0.1)
				(type default)
			)
			(layer "F.Fab")
		)
		(pad "1" smd rect
			(at 0 0 270)
			(size 0.508 0.508)
			(layers "F.Cu" "F.Mask" "F.Paste")
			(net "VR_PVNN_PCH_VINSEN")
		)
		(pad "2" smd rect
			(at 0 0.889 270)
			(size 0.508 0.508)
			(layers "F.Cu" "F.Mask" "F.Paste")
			(net "GND")
		)
		(zone
			(layer "F.Cu")
			(hatch none 0.5)
			(connect_pads
				(clearance 0)
			)
			(min_thickness 0.25)
			(keepout
				(tracks not_allowed)
				(vias allowed)
				(pads allowed)
				(copperpour not_allowed)
				(footprints allowed)
			)
			(placement
				(enabled no)
				(sheetname "")
			)
			(fill
				(thermal_gap 0.5)
				(thermal_bridge_width 0.5)
				(island_removal_mode 0)
			)
			(polygon
				(pts
					(xy 390.92124 -152.262586) (xy 390.92124 -151.754586) (xy 391.30224 -151.754586) (xy 391.30224 -152.262586)
				)
			)
		)
		(zone
			(layer "F.Cu")
			(hatch none 0.5)
			(connect_pads
				(clearance 0)
			)
			(min_thickness 0.25)
			(keepout
				(tracks allowed)
				(vias not_allowed)
				(pads allowed)
				(copperpour not_allowed)
				(footprints allowed)
			)
			(placement
				(enabled no)
				(sheetname "")
			)
			(fill
				(thermal_gap 0.5)
				(thermal_bridge_width 0.5)
				(island_removal_mode 0)
			)
			(polygon
				(pts
					(xy 391.30224 -152.262586) (xy 391.30224 -151.754586) (xy 390.92124 -151.754586) (xy 390.92124 -152.262586)
				)
			)
		)
	)
	(footprint ""
		(layer "F.Cu")
		(at 420.751 -79.614014 180)
		(property "Reference" "U8D3"
			(at 3.09753 1.21666 270)
			(unlocked yes)
			(layer "F.SilkS")
			(effects
				(font
					(size 0.7874 0.5842)
					(thickness 0.1524)
				)
				(justify left)
			)
		)
		(property "Value" ""
			(at 0 0 180)
			(layer "F.Fab")
			(effects
				(font
					(size 1.27 1.27)
				)
			)
		)
		(duplicate_pad_numbers_are_jumpers no)
		(fp_circle
			(center -0.4699 -0.8382)
			(end -0.5969 -0.8382)
			(stroke
				(width 0.254)
				(type default)
			)
			(fill no)
			(layer "F.SilkS")
		)
		(fp_poly
			(pts
				(xy 0.21463 -0.450088) (xy 1.56337 -0.450088) (xy 1.56337 1.75006) (xy 0.21463 1.75006)
			)
			(stroke
				(width 0)
				(type default)
			)
			(fill no)
			(layer "F.CrtYd")
		)
		(fp_line
			(start 1.56337 1.75006)
			(end 0.21463 1.75006)
			(stroke
				(width 0.1)
				(type default)
			)
			(layer "F.Fab")
		)
		(fp_line
			(start 1.56337 -0.450088)
			(end 1.56337 1.75006)
			(stroke
				(width 0.1)
				(type default)
			)
			(layer "F.Fab")
		)
		(fp_line
			(start 0.21463 1.75006)
			(end 0.21463 -0.450088)
			(stroke
				(width 0.1)
				(type default)
			)
			(layer "F.Fab")
		)
		(fp_line
			(start 0.21463 -0.450088)
			(end 1.56337 -0.450088)
			(stroke
				(width 0.1)
				(type default)
			)
			(layer "F.Fab")
		)
		(fp_circle
			(center -0.4699 -0.8382)
			(end -0.5969 -0.8382)
			(stroke
				(width 0.254)
				(type default)
			)
			(fill no)
			(layer "F.Fab")
		)
		(pad "1" smd rect
			(at 0 0 180)
			(size 1.016 0.381)
			(layers "F.Cu" "F.Mask" "F.Paste")
			(net "Net_6471")
		)
		(pad "2" smd rect
			(at 0 0.649986 180)
			(size 1.016 0.381)
			(layers "F.Cu" "F.Mask" "F.Paste")
			(net "IRQ_SML1_PMBUS_ALERT_BUF_N")
		)
		(pad "3" smd rect
			(at 0 1.299972 180)
			(size 1.016 0.381)
			(layers "F.Cu" "F.Mask" "F.Paste")
			(net "GND")
		)
		(pad "4" smd rect
			(at 1.778 1.299972 180)
			(size 1.016 0.381)
			(layers "F.Cu" "F.Mask" "F.Paste")
			(net "IRQ_FORCE_NM_THROTTLE_R_N")
		)
		(pad "5" smd rect
			(at 1.778 0 180)
			(size 1.016 0.381)
			(layers "F.Cu" "F.Mask" "F.Paste")
			(net "P3V3_STBY")
		)
	)
	(footprint ""
		(layer "F.Cu")
		(at 6.9342 -130.302 180)
		(property "Reference" "C1B6"
			(at -0.8382 -0.67818 180)
			(unlocked yes)
			(layer "F.SilkS")
			(effects
				(font
					(size 0.4064 0.254)
					(thickness 0.1524)
				)
				(justify left)
			)
		)
		(property "Value" ""
			(at 0 0 180)
			(layer "F.Fab")
			(effects
				(font
					(size 1.27 1.27)
				)
			)
		)
		(duplicate_pad_numbers_are_jumpers no)
		(fp_poly
			(pts
				(xy 0.3048 -0.1016) (xy 0.3048 0.9906) (xy -0.3048 0.9906) (xy -0.3048 -0.1016)
			)
			(stroke
				(width 0)
				(type default)
			)
			(fill no)
			(layer "F.CrtYd")
		)
		(fp_line
			(start 0.3048 0.9906)
			(end 0.3048 -0.1016)
			(stroke
				(width 0.1)
				(type default)
			)
			(layer "F.Fab")
		)
		(fp_line
			(start 0.3048 -0.1016)
			(end -0.3048 -0.1016)
			(stroke
				(width 0.1)
				(type default)
			)
			(layer "F.Fab")
		)
		(fp_line
			(start -0.3048 0.9906)
			(end 0.3048 0.9906)
			(stroke
				(width 0.1)
				(type default)
			)
			(layer "F.Fab")
		)
		(fp_line
			(start -0.3048 -0.1016)
			(end -0.3048 0.9906)
			(stroke
				(width 0.1)
				(type default)
			)
			(layer "F.Fab")
		)
		(pad "1" smd rect
			(at 0 0 180)
			(size 0.508 0.508)
			(layers "F.Cu" "F.Mask" "F.Paste")
			(net "VR_PVDDQ_KLM_VDD")
		)
		(pad "2" smd rect
			(at 0 0.889 180)
			(size 0.508 0.508)
			(layers "F.Cu" "F.Mask" "F.Paste")
			(net "GND")
		)
		(zone
			(layer "F.Cu")
			(hatch none 0.5)
			(connect_pads
				(clearance 0)
			)
			(min_thickness 0.25)
			(keepout
				(tracks not_allowed)
				(vias allowed)
				(pads allowed)
				(copperpour not_allowed)
				(footprints allowed)
			)
			(placement
				(enabled no)
				(sheetname "")
			)
			(fill
				(thermal_gap 0.5)
				(thermal_bridge_width 0.5)
				(island_removal_mode 0)
			)
			(polygon
				(pts
					(xy 7.1882 -130.937) (xy 6.6802 -130.937) (xy 6.6802 -130.556) (xy 7.1882 -130.556)
				)
			)
		)
		(zone
			(layer "F.Cu")
			(hatch none 0.5)
			(connect_pads
				(clearance 0)
			)
			(min_thickness 0.25)
			(keepout
				(tracks allowed)
				(vias not_allowed)
				(pads allowed)
				(copperpour not_allowed)
				(footprints allowed)
			)
			(placement
				(enabled no)
				(sheetname "")
			)
			(fill
				(thermal_gap 0.5)
				(thermal_bridge_width 0.5)
				(island_removal_mode 0)
			)
			(polygon
				(pts
					(xy 7.1882 -130.556) (xy 6.6802 -130.556) (xy 6.6802 -130.937) (xy 7.1882 -130.937)
				)
			)
		)
	)
	(footprint ""
		(layer "F.Cu")
		(at 441.119006 -41.663874 180)
		(property "Reference" "R25W5"
			(at 0 0 180)
			(layer "F.SilkS")
			(hide yes)
			(effects
				(font
					(size 1.27 1.27)
				)
			)
		)
		(property "Value" "*"
			(at 0.064008 -4.108196 180)
			(unlocked yes)
			(layer "F.Fab")
			(hide yes)
			(effects
				(font
					(size 1.27 1.016)
					(thickness 0.1524)
				)
			)
		)
		(property "Device Type" "120R2F-GP_RCL_GP-120R2F-GP,64.A"
			(at 0.064008 -5.632196 180)
			(unlocked yes)
			(layer "F.Fab")
			(hide yes)
			(effects
				(font
					(size 1.27 1.016)
					(thickness 0.1524)
				)
			)
		)
		(duplicate_pad_numbers_are_jumpers no)
		(fp_line
			(start 0.508 -0.9398)
			(end -0.508 -0.9398)
			(stroke
				(width 0.1524)
				(type default)
			)
			(layer "F.SilkS")
		)
		(fp_line
			(start -0.508 -0.9398)
			(end -0.508 0.9398)
			(stroke
				(width 0.1524)
				(type default)
			)
			(layer "F.SilkS")
		)
		(fp_rect
			(start -0.508 0.9398)
			(end 0.508 -0.9398)
			(stroke
				(width 0)
				(type default)
			)
			(fill no)
			(layer "F.CrtYd")
		)
		(fp_rect
			(start -0.508 0.9398)
			(end 0.508 -0.9398)
			(stroke
				(width 0)
				(type default)
			)
			(fill no)
			(layer "F.Fab")
		)
		(pad "1" smd custom
			(at 0 -0.4445 180)
			(size 0.1397 0.1397)
			(layers "F.Cu" "F.Mask" "F.Paste")
			(net "GND")
			(options
				(clearance outline)
				(anchor circle)
			)
			(primitives
				(gr_poly
					(pts
						(arc
							(start -0.1778 -0.2794)
							(mid -0.249642 -0.249642)
							(end -0.2794 -0.1778)
						)
						(arc
							(start -0.2794 0.1778)
							(mid -0.249642 0.249642)
							(end -0.1778 0.2794)
						)
						(arc
							(start 0.1778 0.2794)
							(mid 0.249642 0.249642)
							(end 0.2794 0.1778)
						)
						(arc
							(start 0.2794 -0.1778)
							(mid 0.249642 -0.249642)
							(end 0.1778 -0.2794)
						)
					)
					(width 0)
					(fill yes)
				)
			)
		)
		(pad "2" smd custom
			(at 0 0.4445 180)
			(size 0.1397 0.1397)
			(layers "F.Cu" "F.Mask" "F.Paste")
			(net "BMC_M_CS_N")
			(options
				(clearance outline)
				(anchor circle)
			)
			(primitives
				(gr_poly
					(pts
						(arc
							(start -0.1778 -0.2794)
							(mid -0.249642 -0.249642)
							(end -0.2794 -0.1778)
						)
						(arc
							(start -0.2794 0.1778)
							(mid -0.249642 0.249642)
							(end -0.1778 0.2794)
						)
						(arc
							(start 0.1778 0.2794)
							(mid 0.249642 0.249642)
							(end 0.2794 0.1778)
						)
						(arc
							(start 0.2794 -0.1778)
							(mid 0.249642 -0.249642)
							(end 0.1778 -0.2794)
						)
					)
					(width 0)
					(fill yes)
				)
			)
		)
	)
	(footprint ""
		(layer "F.Cu")
		(at 491.0455 -42.0624 90)
		(property "Reference" "R9E19"
			(at 0 0 90)
			(layer "F.SilkS")
			(hide yes)
			(effects
				(font
					(size 1.27 1.27)
				)
			)
		)
		(property "Value" ""
			(at 0 0 90)
			(layer "F.Fab")
			(effects
				(font
					(size 1.27 1.27)
				)
			)
		)
		(duplicate_pad_numbers_are_jumpers no)
		(fp_poly
			(pts
				(xy -0.2794 -0.1016) (xy 0.2794 -0.1016) (xy 0.2794 0.9906) (xy -0.2794 0.9906)
			)
			(stroke
				(width 0)
				(type default)
			)
			(fill no)
			(layer "F.CrtYd")
		)
		(fp_line
			(start 0.2794 -0.1016)
			(end -0.2794 -0.1016)
			(stroke
				(width 0.1)
				(type default)
			)
			(layer "F.Fab")
		)
		(fp_line
			(start -0.2794 -0.1016)
			(end -0.2794 0.9906)
			(stroke
				(width 0.1)
				(type default)
			)
			(layer "F.Fab")
		)
		(fp_line
			(start 0.2794 0.9906)
			(end 0.2794 -0.1016)
			(stroke
				(width 0.1)
				(type default)
			)
			(layer "F.Fab")
		)
		(fp_line
			(start -0.2794 0.9906)
			(end 0.2794 0.9906)
			(stroke
				(width 0.1)
				(type default)
			)
			(layer "F.Fab")
		)
		(pad "1" smd rect
			(at 0 0 90)
			(size 0.508 0.508)
			(layers "F.Cu" "F.Mask" "F.Paste")
			(net "RMII_SPRNGVLLE_BMC_PCH_RXD1_R")
		)
		(pad "2" smd rect
			(at 0 0.889 90)
			(size 0.508 0.508)
			(layers "F.Cu" "F.Mask" "F.Paste")
			(net "RMII_SPRNGVLLE_BMC_PCH_RXD1")
		)
		(zone
			(layer "F.Cu")
			(hatch none 0.5)
			(connect_pads
				(clearance 0)
			)
			(min_thickness 0.25)
			(keepout
				(tracks allowed)
				(vias not_allowed)
				(pads allowed)
				(copperpour not_allowed)
				(footprints allowed)
			)
			(placement
				(enabled no)
				(sheetname "")
			)
			(fill
				(thermal_gap 0.5)
				(thermal_bridge_width 0.5)
				(island_removal_mode 0)
			)
			(polygon
				(pts
					(xy 491.2995 -41.8084) (xy 491.2995 -42.3164) (xy 491.6805 -42.3164) (xy 491.6805 -41.8084)
				)
			)
		)
		(zone
			(layer "F.Cu")
			(hatch none 0.5)
			(connect_pads
				(clearance 0)
			)
			(min_thickness 0.25)
			(keepout
				(tracks not_allowed)
				(vias allowed)
				(pads allowed)
				(copperpour not_allowed)
				(footprints allowed)
			)
			(placement
				(enabled no)
				(sheetname "")
			)
			(fill
				(thermal_gap 0.5)
				(thermal_bridge_width 0.5)
				(island_removal_mode 0)
			)
			(polygon
				(pts
					(xy 491.6805 -41.8084) (xy 491.6805 -42.3164) (xy 491.2995 -42.3164) (xy 491.2995 -41.8084)
				)
			)
		)
	)
	(footprint ""
		(layer "F.Cu")
		(at 349.040958 -16.632428)
		(property "Reference" "C12W1"
			(at -0.8382 -0.67818 0)
			(unlocked yes)
			(layer "F.SilkS")
			(effects
				(font
					(size 0.4064 0.254)
					(thickness 0.1524)
				)
				(justify left)
			)
		)
		(property "Value" ""
			(at 0 0 0)
			(layer "F.Fab")
			(effects
				(font
					(size 1.27 1.27)
				)
			)
		)
		(duplicate_pad_numbers_are_jumpers no)
		(fp_poly
			(pts
				(xy 0.3048 -0.1016) (xy 0.3048 0.9906) (xy -0.3048 0.9906) (xy -0.3048 -0.1016)
			)
			(stroke
				(width 0)
				(type default)
			)
			(fill no)
			(layer "F.CrtYd")
		)
		(fp_line
			(start -0.3048 -0.1016)
			(end -0.3048 0.9906)
			(stroke
				(width 0.1)
				(type default)
			)
			(layer "F.Fab")
		)
		(fp_line
			(start -0.3048 0.9906)
			(end 0.3048 0.9906)
			(stroke
				(width 0.1)
				(type default)
			)
			(layer "F.Fab")
		)
		(fp_line
			(start 0.3048 -0.1016)
			(end -0.3048 -0.1016)
			(stroke
				(width 0.1)
				(type default)
			)
			(layer "F.Fab")
		)
		(fp_line
			(start 0.3048 0.9906)
			(end 0.3048 -0.1016)
			(stroke
				(width 0.1)
				(type default)
			)
			(layer "F.Fab")
		)
		(pad "1" smd rect
			(at 0 0)
			(size 0.508 0.508)
			(layers "F.Cu" "F.Mask" "F.Paste")
			(net "VR_PVDDQ_ABC_AIINSEN")
		)
		(pad "2" smd rect
			(at 0 0.889)
			(size 0.508 0.508)
			(layers "F.Cu" "F.Mask" "F.Paste")
			(net "VR_PVDDQ_ABC_VINSEN")
		)
		(zone
			(layer "F.Cu")
			(hatch none 0.5)
			(connect_pads
				(clearance 0)
			)
			(min_thickness 0.25)
			(keepout
				(tracks allowed)
				(vias not_allowed)
				(pads allowed)
				(copperpour not_allowed)
				(footprints allowed)
			)
			(placement
				(enabled no)
				(sheetname "")
			)
			(fill
				(thermal_gap 0.5)
				(thermal_bridge_width 0.5)
				(island_removal_mode 0)
			)
			(polygon
				(pts
					(xy 348.786958 -16.378428) (xy 349.294958 -16.378428) (xy 349.294958 -15.997428) (xy 348.786958 -15.997428)
				)
			)
		)
		(zone
			(layer "F.Cu")
			(hatch none 0.5)
			(connect_pads
				(clearance 0)
			)
			(min_thickness 0.25)
			(keepout
				(tracks not_allowed)
				(vias allowed)
				(pads allowed)
				(copperpour not_allowed)
				(footprints allowed)
			)
			(placement
				(enabled no)
				(sheetname "")
			)
			(fill
				(thermal_gap 0.5)
				(thermal_bridge_width 0.5)
				(island_removal_mode 0)
			)
			(polygon
				(pts
					(xy 348.786958 -15.997428) (xy 349.294958 -15.997428) (xy 349.294958 -16.378428) (xy 348.786958 -16.378428)
				)
			)
		)
	)
	(footprint ""
		(layer "F.Cu")
		(at 339.222588 -117.941598 90)
		(property "Reference" "C6B18"
			(at -0.8382 -0.67818 90)
			(unlocked yes)
			(layer "F.SilkS")
			(effects
				(font
					(size 0.4064 0.254)
					(thickness 0.1524)
				)
				(justify left)
			)
		)
		(property "Value" ""
			(at 0 0 90)
			(layer "F.Fab")
			(effects
				(font
					(size 1.27 1.27)
				)
			)
		)
		(duplicate_pad_numbers_are_jumpers no)
		(fp_poly
			(pts
				(xy 0.3048 -0.1016) (xy 0.3048 0.9906) (xy -0.3048 0.9906) (xy -0.3048 -0.1016)
			)
			(stroke
				(width 0)
				(type default)
			)
			(fill no)
			(layer "F.CrtYd")
		)
		(fp_line
			(start 0.3048 -0.1016)
			(end -0.3048 -0.1016)
			(stroke
				(width 0.1)
				(type default)
			)
			(layer "F.Fab")
		)
		(fp_line
			(start -0.3048 -0.1016)
			(end -0.3048 0.9906)
			(stroke
				(width 0.1)
				(type default)
			)
			(layer "F.Fab")
		)
		(fp_line
			(start 0.3048 0.9906)
			(end 0.3048 -0.1016)
			(stroke
				(width 0.1)
				(type default)
			)
			(layer "F.Fab")
		)
		(fp_line
			(start -0.3048 0.9906)
			(end 0.3048 0.9906)
			(stroke
				(width 0.1)
				(type default)
			)
			(layer "F.Fab")
		)
		(pad "1" smd rect
			(at 0 0 90)
			(size 0.508 0.508)
			(layers "F.Cu" "F.Mask" "F.Paste")
			(net "P3E_CPU0_PE1_PCH_TXP<9>")
		)
		(pad "2" smd rect
			(at 0 0.889 90)
			(size 0.508 0.508)
			(layers "F.Cu" "F.Mask" "F.Paste")
			(net "P3E_CPU0_PE1_PCH_C_TXP<9>")
		)
		(zone
			(layer "F.Cu")
			(hatch none 0.5)
			(connect_pads
				(clearance 0)
			)
			(min_thickness 0.25)
			(keepout
				(tracks allowed)
				(vias not_allowed)
				(pads allowed)
				(copperpour not_allowed)
				(footprints allowed)
			)
			(placement
				(enabled no)
				(sheetname "")
			)
			(fill
				(thermal_gap 0.5)
				(thermal_bridge_width 0.5)
				(island_removal_mode 0)
			)
			(polygon
				(pts
					(xy 339.476588 -117.687598) (xy 339.476588 -118.195598) (xy 339.857588 -118.195598) (xy 339.857588 -117.687598)
				)
			)
		)
		(zone
			(layer "F.Cu")
			(hatch none 0.5)
			(connect_pads
				(clearance 0)
			)
			(min_thickness 0.25)
			(keepout
				(tracks not_allowed)
				(vias allowed)
				(pads allowed)
				(copperpour not_allowed)
				(footprints allowed)
			)
			(placement
				(enabled no)
				(sheetname "")
			)
			(fill
				(thermal_gap 0.5)
				(thermal_bridge_width 0.5)
				(island_removal_mode 0)
			)
			(polygon
				(pts
					(xy 339.857588 -117.687598) (xy 339.857588 -118.195598) (xy 339.476588 -118.195598) (xy 339.476588 -117.687598)
				)
			)
		)
	)
)
